FILE_TYPE=LIBRARY_PARTS;
TIME=' Created/Modified on Tue Dec 28 16:45:18 2010' ;
primitive 'SN74LVC2G07DCKR';
  pin
    '1A':
      PIN_NUMBER='(1)';
      INPUT_LOAD='(-0.01,0.01)';
    '2A':
      PIN_NUMBER='(3)';
      INPUT_LOAD='(-0.01,0.01)';
    '1Y':
      PIN_NUMBER='(6)';
      OUTPUT_LOAD='(1.0,-1.0)';
    '2Y':
      PIN_NUMBER='(4)';
      OUTPUT_LOAD='(1.0,-1.0)';
    'GND':
      PIN_NUMBER='(2)';
      PINUSE='POWER';
    'VCC':
      PIN_NUMBER='(5)';
      PINUSE='POWER';
  end_pin;
  body
    CLASS='IC';
    PART_NAME='SN74LVC2G07DCKR';
    PHYS_DES_PREFIX='U';
  end_body;
end_primitive;
END.
